# BASEBOARD_FAB2 (Tioga Pass) — schematic netlist excerpt (pin names and nets, part order shuffled) for the footprints in the layout excerpt that follows; sources: Cadence DE-HDL packaged netlist, KiCad conversion of Wiwynn_Tioga_Pass_MB.brd

R2T23  RES  2.2 1.0% CHIP  pkg 0603  page 101 : A = P3V3_STBY_MNG ; B = P3V3_STBY_MNG_RGMII
R3M12  RES  100.0 1% CHIP  pkg 0402  page 116 : A = A_PCIEUP_RCOMP_P ; B = A_PCIEUP_RCOMP_N
R1R3  RES  3.32K 1% CHIP  pkg 0402  page 140 : A = P3V3_STBY ; B = PU_NV_WP_N

(kicad_pcb
	(version 20260206)
	(generator "pcbnew")
	(generator_version "10.0")
	(general
		(thickness 1.6)
		(legacy_teardrops no)
	)
	(paper "A4")
	(title_block
		(title "Wiwynn_Tioga_Pass_MB.brd")
		(comment 1 "Tioga Pass / footprints 2588-2590 of 4770")
	)
	(layers
		(0 "F.Cu" signal "TOP")
		(4 "In1.Cu" signal "L2GND")
		(6 "In2.Cu" signal "L3")
		(8 "In3.Cu" signal "L4GND")
		(10 "In4.Cu" signal "L5")
		(12 "In5.Cu" signal "L6GND")
		(14 "In6.Cu" signal "L7VCC")
		(16 "In7.Cu" signal "L8VCC")
		(18 "In8.Cu" signal "L9GND")
		(20 "In9.Cu" signal "L10")
		(22 "In10.Cu" signal "L11GND")
		(24 "In11.Cu" signal "L12")
		(26 "In12.Cu" signal "L13GND")
		(2 "B.Cu" signal "BOTTOM")
		(9 "F.Adhes" user "F.Adhesive")
		(11 "B.Adhes" user "B.Adhesive")
		(13 "F.Paste" user "Package Geometry/Pastemask Top")
		(15 "B.Paste" user "Package Geometry/Pastemask Bottom")
		(5 "F.SilkS" user "Ref Des/Silkscreen Top")
		(7 "B.SilkS" user "Ref Des/Silkscreen Bottom")
		(1 "F.Mask" user "Board Geometry/Soldermask Top")
		(3 "B.Mask" user "Board Geometry/Soldermask Bottom")
		(17 "Dwgs.User" user "User.Drawings")
		(19 "Cmts.User" user "User.Comments")
		(21 "Eco1.User" user "User.Eco1")
		(23 "Eco2.User" user "User.Eco2")
		(25 "Edge.Cuts" user "Board Geometry/Outline")
		(27 "Margin" user)
		(31 "F.CrtYd" user "Package Geometry/Place Bound Top")
		(29 "B.CrtYd" user "Package Geometry/Place Bound Bottom")
		(35 "F.Fab" user "Ref Des/Assembly Top")
		(33 "B.Fab" user "Ref Des/Assembly Bottom")
	)
	(footprint ""
		(layer "B.Cu")
		(at 474.85046 -27.29992 180)
		(property "Reference" "R2T23"
			(at 0 0 0)
			(layer "B.SilkS")
			(hide yes)
			(effects
				(font
					(size 1.27 1.27)
				)
				(justify mirror)
			)
		)
		(property "Value" ""
			(at 0 0 0)
			(layer "B.Fab")
			(effects
				(font
					(size 1.27 1.27)
				)
				(justify mirror)
			)
		)
		(duplicate_pad_numbers_are_jumpers no)
		(fp_poly
			(pts
				(xy 0.4953 -0.2032) (xy -0.4953 -0.2032) (xy -0.4953 1.6002) (xy 0.4953 1.6002)
			)
			(stroke
				(width 0)
				(type default)
			)
			(fill no)
			(layer "B.CrtYd")
		)
		(fp_line
			(start 0.4953 1.6002)
			(end 0.4953 -0.2032)
			(stroke
				(width 0.1)
				(type default)
			)
			(layer "B.Fab")
		)
		(fp_line
			(start 0.4953 -0.2032)
			(end -0.4953 -0.2032)
			(stroke
				(width 0.1)
				(type default)
			)
			(layer "B.Fab")
		)
		(fp_line
			(start -0.4953 1.6002)
			(end 0.4953 1.6002)
			(stroke
				(width 0.1)
				(type default)
			)
			(layer "B.Fab")
		)
		(fp_line
			(start -0.4953 -0.2032)
			(end -0.4953 1.6002)
			(stroke
				(width 0.1)
				(type default)
			)
			(layer "B.Fab")
		)
		(pad "1" smd rect
			(at 0 0)
			(size 0.762 0.889)
			(layers "B.Cu" "B.Mask" "B.Paste")
			(net "P3V3_STBY_MNG")
		)
		(pad "2" smd rect
			(at 0 1.397)
			(size 0.762 0.889)
			(layers "B.Cu" "B.Mask" "B.Paste")
			(net "P3V3_STBY_MNG_RGMII")
		)
		(zone
			(layer "B.Cu")
			(hatch none 0.5)
			(connect_pads
				(clearance 0)
			)
			(min_thickness 0.25)
			(keepout
				(tracks not_allowed)
				(vias allowed)
				(pads allowed)
				(copperpour not_allowed)
				(footprints allowed)
			)
			(placement
				(enabled no)
				(sheetname "")
			)
			(fill
				(thermal_gap 0.5)
				(thermal_bridge_width 0.5)
				(island_removal_mode 0)
			)
			(polygon
				(pts
					(xy 474.46946 -28.25242) (xy 474.46946 -27.74442) (xy 475.23146 -27.74442) (xy 475.23146 -28.25242)
				)
			)
		)
		(zone
			(layer "B.Cu")
			(hatch none 0.5)
			(connect_pads
				(clearance 0)
			)
			(min_thickness 0.25)
			(keepout
				(tracks allowed)
				(vias not_allowed)
				(pads allowed)
				(copperpour not_allowed)
				(footprints allowed)
			)
			(placement
				(enabled no)
				(sheetname "")
			)
			(fill
				(thermal_gap 0.5)
				(thermal_bridge_width 0.5)
				(island_removal_mode 0)
			)
			(polygon
				(pts
					(xy 475.23146 -28.25242) (xy 475.23146 -27.74442) (xy 474.46946 -27.74442) (xy 474.46946 -28.25242)
				)
			)
		)
	)
	(footprint ""
		(layer "B.Cu")
		(at 488.696 -18.161 -90)
		(property "Reference" "R1R3"
			(at 0.8382 -0.67818 270)
			(unlocked yes)
			(layer "B.SilkS")
			(effects
				(font
					(size 0.4064 0.254)
					(thickness 0.1524)
				)
				(justify left mirror)
			)
		)
		(property "Value" ""
			(at 0 0 90)
			(layer "B.Fab")
			(effects
				(font
					(size 1.27 1.27)
				)
				(justify mirror)
			)
		)
		(duplicate_pad_numbers_are_jumpers no)
		(fp_poly
			(pts
				(xy 0.2794 -0.1016) (xy -0.2794 -0.1016) (xy -0.2794 0.9906) (xy 0.2794 0.9906)
			)
			(stroke
				(width 0)
				(type default)
			)
			(fill no)
			(layer "B.CrtYd")
		)
		(fp_line
			(start -0.2794 0.9906)
			(end -0.2794 -0.1016)
			(stroke
				(width 0.1)
				(type default)
			)
			(layer "B.Fab")
		)
		(fp_line
			(start 0.2794 0.9906)
			(end -0.2794 0.9906)
			(stroke
				(width 0.1)
				(type default)
			)
			(layer "B.Fab")
		)
		(fp_line
			(start -0.2794 -0.1016)
			(end 0.2794 -0.1016)
			(stroke
				(width 0.1)
				(type default)
			)
			(layer "B.Fab")
		)
		(fp_line
			(start 0.2794 -0.1016)
			(end 0.2794 0.9906)
			(stroke
				(width 0.1)
				(type default)
			)
			(layer "B.Fab")
		)
		(pad "1" smd rect
			(at 0 0 90)
			(size 0.508 0.508)
			(layers "B.Cu" "B.Mask" "B.Paste")
			(net "P3V3_STBY")
		)
		(pad "2" smd rect
			(at 0 0.889 90)
			(size 0.508 0.508)
			(layers "B.Cu" "B.Mask" "B.Paste")
			(net "PU_NV_WP_N")
		)
		(zone
			(layer "B.Cu")
			(hatch none 0.5)
			(connect_pads
				(clearance 0)
			)
			(min_thickness 0.25)
			(keepout
				(tracks not_allowed)
				(vias allowed)
				(pads allowed)
				(copperpour not_allowed)
				(footprints allowed)
			)
			(placement
				(enabled no)
				(sheetname "")
			)
			(fill
				(thermal_gap 0.5)
				(thermal_bridge_width 0.5)
				(island_removal_mode 0)
			)
			(polygon
				(pts
					(xy 488.061 -17.907) (xy 488.061 -18.415) (xy 488.442 -18.415) (xy 488.442 -17.907)
				)
			)
		)
		(zone
			(layer "B.Cu")
			(hatch none 0.5)
			(connect_pads
				(clearance 0)
			)
			(min_thickness 0.25)
			(keepout
				(tracks allowed)
				(vias not_allowed)
				(pads allowed)
				(copperpour not_allowed)
				(footprints allowed)
			)
			(placement
				(enabled no)
				(sheetname "")
			)
			(fill
				(thermal_gap 0.5)
				(thermal_bridge_width 0.5)
				(island_removal_mode 0)
			)
			(polygon
				(pts
					(xy 488.442 -17.907) (xy 488.442 -18.415) (xy 488.061 -18.415) (xy 488.061 -17.907)
				)
			)
		)
	)
	(footprint ""
		(layer "B.Cu")
		(at 388.0104 -125.507242 -90)
		(property "Reference" "R3M12"
			(at 0 0 90)
			(layer "B.SilkS")
			(hide yes)
			(effects
				(font
					(size 1.27 1.27)
				)
				(justify mirror)
			)
		)
		(property "Value" ""
			(at 0 0 90)
			(layer "B.Fab")
			(effects
				(font
					(size 1.27 1.27)
				)
				(justify mirror)
			)
		)
		(duplicate_pad_numbers_are_jumpers no)
		(fp_poly
			(pts
				(xy 0.2794 -0.1016) (xy -0.2794 -0.1016) (xy -0.2794 0.9906) (xy 0.2794 0.9906)
			)
			(stroke
				(width 0)
				(type default)
			)
			(fill no)
			(layer "B.CrtYd")
		)
		(fp_line
			(start -0.2794 0.9906)
			(end -0.2794 -0.1016)
			(stroke
				(width 0.1)
				(type default)
			)
			(layer "B.Fab")
		)
		(fp_line
			(start 0.2794 0.9906)
			(end -0.2794 0.9906)
			(stroke
				(width 0.1)
				(type default)
			)
			(layer "B.Fab")
		)
		(fp_line
			(start -0.2794 -0.1016)
			(end 0.2794 -0.1016)
			(stroke
				(width 0.1)
				(type default)
			)
			(layer "B.Fab")
		)
		(fp_line
			(start 0.2794 -0.1016)
			(end 0.2794 0.9906)
			(stroke
				(width 0.1)
				(type default)
			)
			(layer "B.Fab")
		)
		(pad "1" smd rect
			(at 0 0 90)
			(size 0.508 0.508)
			(layers "B.Cu" "B.Mask" "B.Paste")
			(net "A_PCIEUP_RCOMP_P")
		)
		(pad "2" smd rect
			(at 0 0.889 90)
			(size 0.508 0.508)
			(layers "B.Cu" "B.Mask" "B.Paste")
			(net "A_PCIEUP_RCOMP_N")
		)
		(zone
			(layer "B.Cu")
			(hatch none 0.5)
			(connect_pads
				(clearance 0)
			)
			(min_thickness 0.25)
			(keepout
				(tracks not_allowed)
				(vias allowed)
				(pads allowed)
				(copperpour not_allowed)
				(footprints allowed)
			)
			(placement
				(enabled no)
				(sheetname "")
			)
			(fill
				(thermal_gap 0.5)
				(thermal_bridge_width 0.5)
				(island_removal_mode 0)
			)
			(polygon
				(pts
					(xy 387.3754 -125.253242) (xy 387.3754 -125.761242) (xy 387.7564 -125.761242) (xy 387.7564 -125.253242)
				)
			)
		)
		(zone
			(layer "B.Cu")
			(hatch none 0.5)
			(connect_pads
				(clearance 0)
			)
			(min_thickness 0.25)
			(keepout
				(tracks allowed)
				(vias not_allowed)
				(pads allowed)
				(copperpour not_allowed)
				(footprints allowed)
			)
			(placement
				(enabled no)
				(sheetname "")
			)
			(fill
				(thermal_gap 0.5)
				(thermal_bridge_width 0.5)
				(island_removal_mode 0)
			)
			(polygon
				(pts
					(xy 387.7564 -125.253242) (xy 387.7564 -125.761242) (xy 387.3754 -125.761242) (xy 387.3754 -125.253242)
				)
			)
		)
	)
)
